FILE_TYPE = CONNECTIVITY;
{Allegro Design Entry HDL 17.2-2016 S081 (4005846) 1/11/2022}
"PAGE_NUMBER" = 36;
0"NC";
END.
